P  UNITS CUST 0
C   
C   vSure IPC 356 OUTPUT.  
C
C   FTP Site : valor.com
C   WEB Site : http://www.valor.com 
C
P   NNAME00000     I2C_C_BUF_SCL_CONN                                       
P   NNAME00001     I2C_C_BUF_SDA_CONN                                       
P   NNAME00002     PEER_TRAY_PRESENT                                        
P   NNAME00003     SD_LATCH_RELEASE                                         
P   NNAME00004     SELF_TRAY_PRESENT                                        
P   NNAME00005     STRADDLE_I2C_C_SDA                                       
P   NNAME00006     STRADDLE_I2C_C_SCL                                       
P   NNAME00007     TRAY_PRESENT_OUT_NET_B                                   
P   NNAME00008     TRAY_PRESENT_OUT#_C                                      
P   NNAME00009     I2C_C_BUF_SCLOUT                                         
P   NNAME00010     I2C_C_BUF_SDAOUT                                         
P   NNAME00011     I2C_C_BUF_READY                                          
P   NNAME00012     TRAY_PRESENT_OUT_NET                                     
P   NNAME00013     I2C_C_BUF_SCLIN                                          
P   NNAME00014     I2C_C_BUF_SDAIN                                          
317$NONE$                       D0340PA00X+059906Y+009055               S0      
317$NONE$                       D0340PA00X+059906Y+005906               S0      
317$NONE$                       D1580PA00X+060071Y+013691               S0      
317$NONE$                       D1580PA00X+060071Y+031191               S0      
317$NONE$                       D0860PA00X-002362Y+001575               S0      
317$NONE$                       D0860PA00X+131229Y+001575               S0      
317$NONE$                       D0860PA00X-002362Y+093701               S0      
327$NONE$                             A01X-002362Y+006279X0500Y0500     S0      
327$NONE$                             A01X-002362Y+091627X0500Y0500     S0      
327$NONE$                             A01X+129770Y+005847X0500Y0500     S0      
317P3V3                         D0240PA01X+004131Y+038746               S0      
317P3V3                         D0340PA01X+004581Y+038807               S0      
327P3V3                               A01X+060710Y+034380X0740Y1220     S0      
317P3V3                         D0220PA01X+005109Y+039073               S0      
317P3V3                         D0220PA01X+005271Y+035240               S0      
317P3V3                         D0220PA01X+004833Y+035245               S0      
317P3V3                         D0220PA01X+006005Y+039069               S0      
317P3V3                         D0220PA01X+005740Y+035246               S0      
317P3V3                         D0220PA01X+005535Y+039077               S0      
317P3V3                         D0220PA01X+052280Y+032600               S0      
317P3V3                         D0220PA01X+053800Y+029670               S0      
317P3V3                         D0340PA01X+061280Y+040864               S0      
327P3V3                               A01X+004990Y+037965X0160Y0600     S0      
327P3V3                               A04X-002756Y+030720X1970Y0320     S0      
327P3V3                               A04X-002756Y+031220X1970Y0320     S0      
317P3V3             VIA        MD0280PA04X+002040Y+030994               S0      
317P3V3             VIA        MD0280PA04X+004940Y+032644               S0      
317P3V3             VIA        MD0280PA04X+005340Y+038894               S0      
317P3V3             VIA        MD0280PA04X+057950Y+033350               S0      
317P3V3             VIA        MD0280PA04X+060540Y+040944               S0      
317P3V3             VIA        MD0160PA00X+003750Y+038650               S0      
317P3V3             VIA        MD0160PA00X+004833Y+034851               S0      
317P3V3             VIA        MD0160PA00X+005109Y+039448               S0      
317P3V3             VIA        MD0160PA00X+052050Y+033100               S0      
317P3V3             VIA        MD0160PA00X+005271Y+034863               S0      
317P3V3             VIA        MD0160PA00X+054390Y+031400               S0      
317P3V3             VIA        MD0160PA00X+005535Y+039467               S0      
317P3V3             VIA        MD0160PA00X+005740Y+034868               S0      
317P3V3             VIA        MD0160PA00X+059550Y+033750               S0      
317P3V3             VIA        MD0160PA00X+059550Y+034200               S0      
317P3V3             VIA        MD0160PA00X+006005Y+039467               S0      
317P3V3             VIA        MD0160PA00X+060000Y+033750               S0      
317P3V3             VIA        MD0160PA00X+060000Y+034200               S0      
317P3V3             VIA        MD0160PA00X+061280Y+041300               S0      
327GND                                A01X+055050Y+032234X0550Y0450     S0      
317GND                          D0240PA01X+004131Y+039106               S0      
327GND                                A01X+047290Y+019024X0550Y0450     S0      
327GND                                A01X+000020Y+019742X0550Y0450     S0      
327GND                                A01X+000930Y+019742X0550Y0450     S0      
317GND                          D0340PA01X+003813Y+037993               S0      
317GND                          D0340PA01X+003811Y+036313               S0      
317GND                          D0340PA01X+004581Y+039367               S0      
317GND                          D0340PA01X+054250Y+027477               S0      
317GND                          D0340PA01X+054250Y+025817               S0      
317GND                          D0340PA01X+063449Y+007760               S0      
327GND                                A01X+048763Y+019809X0950Y0900     S0      
327GND                                A01X+051299Y+019816X0950Y0900     S0      
327GND                                A01X+053814Y+019818X0950Y0900     S0      
317GND                          D0220PA01X+053364Y+032640               S0      
317GND                          D0220PA01X+057771Y+006692               S0      
317GND                          D0300PA01X+052516Y+031585               S0      
317GND                          D0300PA01X+052514Y+030076               S0      
327GND                                A01X+005758Y+036335X0160Y0600     S0      
317GND                          D0410PA00X+060071Y+021441               S0      
317GND                          D0410PA00X+060071Y+023441               S0      
317GND                          D0410PA00X+059071Y+020441               S0      
317GND                          D0410PA00X+059071Y+022441               S0      
317GND                          D0410PA00X+059071Y+024441               S0      
317GND                          D0410PA00X+060071Y+025693               S0      
317GND                          D0410PA00X+059071Y+025693               S0      
317GND                          D0410PA00X+058071Y+025693               S0      
317GND                          D0410PA00X+057071Y+025693               S0      
317GND                          D0410PA00X+060071Y+026693               S0      
317GND                          D0410PA00X+059071Y+026693               S0      
317GND                          D0410PA00X+058071Y+026693               S0      
317GND                          D0410PA00X+057071Y+026693               S0      
317GND                          D0410PA00X+060071Y+027693               S0      
317GND                          D0410PA00X+059071Y+027693               S0      
317GND                          D0410PA00X+058071Y+027693               S0      
317GND                          D0410PA00X+057071Y+027693               S0      
317GND                          D0410PA00X+060071Y+028693               S0      
317GND                          D0410PA00X+059071Y+028693               S0      
317GND                          D0410PA00X+058071Y+028693               S0      
317GND                          D0410PA00X+057071Y+028693               S0      
317GND                          D1580PA00X+058921Y+044882               S0      
317GND                          D1580PA00X+049866Y+002362               S0      
327GND                                A04X-002501Y+021342X2480Y3720     S0      
327GND                                A04X-002201Y+022272X0010Y0010     S0      
327GND                                A04X-002201Y+021342X0010Y0010     S0      
327GND                                A04X-002201Y+020412X0010Y0010     S0      
327GND                                A04X-002501Y+025342X2480Y3720     S0      
327GND                                A04X-002201Y+026272X0010Y0010     S0      
327GND                                A04X-002201Y+025342X0010Y0010     S0      
327GND                                A04X-002201Y+024412X0010Y0010     S0      
327GND                                A04X-002501Y+028307X2480Y1650     S0      
327GND                                A04X-002201Y+028307X0010Y0010     S0      
327GND                                A01X-002501Y+028307X2480Y1650     S0      
327GND                                A01X-002651Y+028307X0010Y0010     S0      
327GND                                A01X-002501Y+025342X2480Y3720     S0      
327GND                                A01X-002651Y+026272X0010Y0010     S0      
327GND                                A01X-002651Y+025342X0010Y0010     S0      
327GND                                A01X-002651Y+024412X0010Y0010     S0      
327GND                                A01X-002501Y+021342X2480Y3720     S0      
327GND                                A01X-002651Y+022272X0010Y0010     S0      
327GND                                A01X-002651Y+021342X0010Y0010     S0      
327GND                                A01X-002651Y+020412X0010Y0010     S0      
327GND                                A04X-002756Y+030220X1970Y0320     S0      
327GND                                A04X-002756Y+033720X1970Y0320     S0      
327GND                                A04X-002756Y+034720X1970Y0320     S0      
327GND                                A04X-002756Y+035720X1970Y0320     S0      
327GND                                A01X-002756Y+035720X1970Y0320     S0      
327GND                                A01X-002756Y+032720X1970Y0320     S0      
327GND                                A01X-002756Y+031220X1970Y0320     S0      
327GND                                A01X-002756Y+030720X1970Y0320     S0      
327GND                                A01X+042150Y+019230X1100Y0550     S0      
327GND                                A01X+043500Y+019230X1100Y0550     S0      
327GND                                A01X+044850Y+019230X1100Y0550     S0      
327GND                                A01X+046200Y+019230X1100Y0550     S0      
317GND                          D1400PA00X+003016Y+041535               S0      
317GND                          D1400PA00X+003016Y+006102               S0      
317GND              VIA        MD0280PA04X+011440Y+030894               S0      
317GND              VIA        MD0280PA04X+020840Y+043344               S0      
317GND              VIA        MD0280PA04X+024790Y+023494               S0      
317GND              VIA        MD0280PA04X+024890Y+003594               S0      
317GND              VIA        MD0280PA04X+028240Y+031244               S0      
317GND              VIA        MD0280PA04X+036440Y+043094               S0      
317GND              VIA        MD0280PA04X+036540Y+003594               S0      
317GND              VIA        MD0280PA04X+039324Y+023999               S0      
317GND              VIA        MD0280PA04X+039402Y+030826               S0      
317GND              VIA        MD0280PA04X+046905Y+044369               S0      
317GND              VIA        MD0280PA04X+004740Y+021494               S0      
317GND              VIA        MD0280PA04X+004840Y+027494               S0      
317GND              VIA        MD0280PA04X+048540Y+037244               S0      
317GND              VIA        MD0280PA04X+050740Y+019644               S0      
317GND              VIA        MD0280PA04X+050990Y+043194               S0      
317GND              VIA        MD0280PA04X+052590Y+003344               S0      
317GND              VIA        MD0280PA04X+053490Y+026144               S0      
317GND              VIA        MD0280PA04X+054300Y+019750               S0      
317GND              VIA        MD0280PA04X+056869Y+006641               S0      
317GND              VIA        MD0280PA04X+006740Y+041694               S0      
317GND              VIA        MD0280PA04X+007600Y+003200               S0      
317GND              VIA        MD0280PA04X+007840Y+037194               S0      
317GND              VIA        MD0160PA00X-000260Y+020694               S0      
317GND              VIA        MD0160PA00X-000260Y+021694               S0      
317GND              VIA        MD0160PA00X-000260Y+022694               S0      
317GND              VIA        MD0160PA00X-000260Y+023694               S0      
317GND              VIA        MD0160PA00X-000260Y+024694               S0      
317GND              VIA        MD0160PA00X-000260Y+025694               S0      
317GND              VIA        MD0160PA00X-000260Y+026694               S0      
317GND              VIA        MD0160PA00X-000260Y+027694               S0      
317GND              VIA        MD0160PA00X-000260Y+031644               S0      
317GND              VIA        MD0160PA00X-000295Y+030220               S0      
317GND              VIA        MD0160PA00X-000660Y+034720               S0      
317GND              VIA        MD0160PA00X-000660Y+035720               S0      
317GND              VIA        MD0160PA00X-000694Y+031625               S0      
317GND              VIA        MD0160PA00X-000710Y+032720               S0      
317GND              VIA        MD0160PA00X-000710Y+033720               S0      
317GND              VIA        MD0160PA00X+010533Y+044296               S0      
317GND              VIA        MD0160PA00X+011533Y+033796               S0      
317GND              VIA        MD0160PA00X+011533Y+035796               S0      
317GND              VIA        MD0160PA00X+011533Y+037796               S0      
317GND              VIA        MD0160PA00X+011533Y+041796               S0      
317GND              VIA        MD0160PA00X+011640Y+026694               S0      
317GND              VIA        MD0160PA00X+011640Y+028694               S0      
317GND              VIA        MD0160PA00X+011642Y+004648               S0      
317GND              VIA        MD0160PA00X+011740Y+020694               S0      
317GND              VIA        MD0160PA00X+011740Y+022694               S0      
317GND              VIA        MD0160PA00X+011740Y+024694               S0      
317GND              VIA        MD0160PA00X+011750Y+046550               S0      
317GND              VIA        MD0160PA00X+013200Y+044250               S0      
317GND              VIA        MD0160PA00X+013533Y+033796               S0      
317GND              VIA        MD0160PA00X+013533Y+035796               S0      
317GND              VIA        MD0160PA00X+013533Y+037796               S0      
317GND              VIA        MD0160PA00X+013533Y+041796               S0      
317GND              VIA        MD0160PA00X+013642Y+004648               S0      
317GND              VIA        MD0160PA00X+013642Y+000648               S0      
317GND              VIA        MD0160PA00X+013740Y+020694               S0      
317GND              VIA        MD0160PA00X+013740Y+022694               S0      
317GND              VIA        MD0160PA00X+013740Y+024694               S0      
317GND              VIA        MD0160PA00X+013740Y+026694               S0      
317GND              VIA        MD0160PA00X+013740Y+028694               S0      
317GND              VIA        MD0160PA00X+013990Y+046544               S0      
317GND              VIA        MD0160PA00X+015500Y+044200               S0      
317GND              VIA        MD0160PA00X+015533Y+033796               S0      
317GND              VIA        MD0160PA00X+015533Y+035796               S0      
317GND              VIA        MD0160PA00X+015533Y+037796               S0      
317GND              VIA        MD0160PA00X+015533Y+041796               S0      
317GND              VIA        MD0160PA00X+015642Y+002648               S0      
317GND              VIA        MD0160PA00X+015642Y+004648               S0      
317GND              VIA        MD0160PA00X+015642Y+000648               S0      
317GND              VIA        MD0160PA00X+015740Y+020694               S0      
317GND              VIA        MD0160PA00X+015740Y+022694               S0      
317GND              VIA        MD0160PA00X+015740Y+024694               S0      
317GND              VIA        MD0160PA00X+015740Y+026694               S0      
317GND              VIA        MD0160PA00X+015740Y+028694               S0      
317GND              VIA        MD0160PA00X+015990Y+046544               S0      
317GND              VIA        MD0160PA00X+001642Y+002648               S0      
317GND              VIA        MD0160PA00X+001642Y+000648               S0      
317GND              VIA        MD0160PA00X+001740Y+020694               S0      
317GND              VIA        MD0160PA00X+001740Y+021694               S0      
317GND              VIA        MD0160PA00X+001740Y+025694               S0      
317GND              VIA        MD0160PA00X+001740Y+026694               S0      
317GND              VIA        MD0160PA00X+001740Y+027694               S0      
317GND              VIA        MD0160PA00X+001740Y+028694               S0      
317GND              VIA        MD0160PA00X+017533Y+033796               S0      
317GND              VIA        MD0160PA00X+017533Y+035796               S0      
317GND              VIA        MD0160PA00X+017533Y+037796               S0      
317GND              VIA        MD0160PA00X+017533Y+041796               S0      
317GND              VIA        MD0160PA00X+017550Y+044200               S0      
317GND              VIA        MD0160PA00X+017642Y+002648               S0      
317GND              VIA        MD0160PA00X+017642Y+004648               S0      
317GND              VIA        MD0160PA00X+017642Y+000648               S0      
317GND              VIA        MD0160PA00X+017740Y+020644               S0      
317GND              VIA        MD0160PA00X+017740Y+022694               S0      
317GND              VIA        MD0160PA00X+017740Y+024694               S0      
317GND              VIA        MD0160PA00X+017740Y+026694               S0      
317GND              VIA        MD0160PA00X+017740Y+028694               S0      
317GND              VIA        MD0160PA00X+017990Y+046544               S0      
317GND              VIA        MD0160PA00X+019533Y+033796               S0      
317GND              VIA        MD0160PA00X+019533Y+035796               S0      
317GND              VIA        MD0160PA00X+019533Y+037796               S0      
317GND              VIA        MD0160PA00X+019533Y+041796               S0      
317GND              VIA        MD0160PA00X+019600Y+044250               S0      
317GND              VIA        MD0160PA00X+019642Y+002648               S0      
317GND              VIA        MD0160PA00X+019642Y+004648               S0      
317GND              VIA        MD0160PA00X+019642Y+000648               S0      
317GND              VIA        MD0160PA00X+019740Y+020644               S0      
317GND              VIA        MD0160PA00X+019740Y+022694               S0      
317GND              VIA        MD0160PA00X+019740Y+024694               S0      
317GND              VIA        MD0160PA00X+019740Y+026694               S0      
317GND              VIA        MD0160PA00X+019740Y+028694               S0      
317GND              VIA        MD0160PA00X+001990Y+046544               S0      
317GND              VIA        MD0160PA00X+019990Y+046544               S0      
317GND              VIA        MD0160PA00X+021533Y+033796               S0      
317GND              VIA        MD0160PA00X+021533Y+035796               S0      
317GND              VIA        MD0160PA00X+021533Y+037796               S0      
317GND              VIA        MD0160PA00X+021533Y+041796               S0      
317GND              VIA        MD0160PA00X+021583Y+044246               S0      
317GND              VIA        MD0160PA00X+021642Y+002648               S0      
317GND              VIA        MD0160PA00X+021642Y+004648               S0      
317GND              VIA        MD0160PA00X+021642Y+000648               S0      
317GND              VIA        MD0160PA00X+021740Y+020644               S0      
317GND              VIA        MD0160PA00X+021740Y+022694               S0      
317GND              VIA        MD0160PA00X+021740Y+024694               S0      
317GND              VIA        MD0160PA00X+021740Y+026694               S0      
317GND              VIA        MD0160PA00X+021740Y+028694               S0      
317GND              VIA        MD0160PA00X+021990Y+046544               S0      
317GND              VIA        MD0160PA00X+002200Y+037450               S0      
317GND              VIA        MD0160PA00X+002200Y+038750               S0      
317GND              VIA        MD0160PA00X+023533Y+033796               S0      
317GND              VIA        MD0160PA00X+023533Y+035796               S0      
317GND              VIA        MD0160PA00X+023533Y+037796               S0      
317GND              VIA        MD0160PA00X+023533Y+041796               S0      
317GND              VIA        MD0160PA00X+023583Y+044246               S0      
317GND              VIA        MD0160PA00X+023642Y+002648               S0      
317GND              VIA        MD0160PA00X+023642Y+004648               S0      
317GND              VIA        MD0160PA00X+023642Y+000648               S0      
317GND              VIA        MD0160PA00X+023740Y+020644               S0      
317GND              VIA        MD0160PA00X+023740Y+022694               S0      
317GND              VIA        MD0160PA00X+023740Y+024694               S0      
317GND              VIA        MD0160PA00X+023740Y+026694               S0      
317GND              VIA        MD0160PA00X+023740Y+028694               S0      
317GND              VIA        MD0160PA00X+023990Y+046544               S0      
317GND              VIA        MD0160PA00X+002500Y+034300               S0      
317GND              VIA        MD0160PA00X+002550Y+035300               S0      
317GND              VIA        MD0160PA00X+025533Y+033796               S0      
317GND              VIA        MD0160PA00X+025533Y+035796               S0      
317GND              VIA        MD0160PA00X+025533Y+037796               S0      
317GND              VIA        MD0160PA00X+025533Y+041796               S0      
317GND              VIA        MD0160PA00X+025583Y+044246               S0      
317GND              VIA        MD0160PA00X+025642Y+002648               S0      
317GND              VIA        MD0160PA00X+025642Y+004648               S0      
317GND              VIA        MD0160PA00X+025642Y+000648               S0      
317GND              VIA        MD0160PA00X+025740Y+020644               S0      
317GND              VIA        MD0160PA00X+025740Y+022694               S0      
317GND              VIA        MD0160PA00X+025740Y+024694               S0      
317GND              VIA        MD0160PA00X+025740Y+026694               S0      
317GND              VIA        MD0160PA00X+025740Y+028694               S0      
317GND              VIA        MD0160PA00X+025990Y+046544               S0      
317GND              VIA        MD0160PA00X+002740Y+020694               S0      
317GND              VIA        MD0160PA00X+002740Y+021694               S0      
317GND              VIA        MD0160PA00X+002740Y+025694               S0      
317GND              VIA        MD0160PA00X+002740Y+026694               S0      
317GND              VIA        MD0160PA00X+002740Y+027694               S0      
317GND              VIA        MD0160PA00X+002740Y+028694               S0      
317GND              VIA        MD0160PA00X+027533Y+033796               S0      
317GND              VIA        MD0160PA00X+027533Y+035796               S0      
317GND              VIA        MD0160PA00X+027533Y+037796               S0      
317GND              VIA        MD0160PA00X+027533Y+041796               S0      
317GND              VIA        MD0160PA00X+027583Y+044246               S0      
317GND              VIA        MD0160PA00X+027642Y+002648               S0      
317GND              VIA        MD0160PA00X+027642Y+004648               S0      
317GND              VIA        MD0160PA00X+027642Y+000648               S0      
317GND              VIA        MD0160PA00X+027740Y+020644               S0      
317GND              VIA        MD0160PA00X+027740Y+022694               S0      
317GND              VIA        MD0160PA00X+027740Y+024694               S0      
317GND              VIA        MD0160PA00X+027740Y+026694               S0      
317GND              VIA        MD0160PA00X+027940Y+028694               S0      
317GND              VIA        MD0160PA00X+027990Y+046544               S0      
317GND              VIA        MD0160PA00X+029533Y+033796               S0      
317GND              VIA        MD0160PA00X+029533Y+035796               S0      
317GND              VIA        MD0160PA00X+029533Y+037796               S0      
317GND              VIA        MD0160PA00X+029533Y+041796               S0      
317GND              VIA        MD0160PA00X+029583Y+044246               S0      
317GND              VIA        MD0160PA00X+029642Y+002648               S0      
317GND              VIA        MD0160PA00X+029642Y+004648               S0      
317GND              VIA        MD0160PA00X+029642Y+000648               S0      
317GND              VIA        MD0160PA00X+029740Y+020644               S0      
317GND              VIA        MD0160PA00X+029740Y+022694               S0      
317GND              VIA        MD0160PA00X+029740Y+024694               S0      
317GND              VIA        MD0160PA00X+029740Y+026694               S0      
317GND              VIA        MD0160PA00X+029990Y+046544               S0      
317GND              VIA        MD0160PA00X+030040Y+028694               S0      
317GND              VIA        MD0160PA00X+031533Y+033796               S0      
317GND              VIA        MD0160PA00X+031533Y+035796               S0      
317GND              VIA        MD0160PA00X+031533Y+037796               S0      
317GND              VIA        MD0160PA00X+031533Y+041796               S0      
317GND              VIA        MD0160PA00X+031583Y+044246               S0      
317GND              VIA        MD0160PA00X+031642Y+002648               S0      
317GND              VIA        MD0160PA00X+031642Y+004648               S0      
317GND              VIA        MD0160PA00X+031642Y+000648               S0      
317GND              VIA        MD0160PA00X+031740Y+020644               S0      
317GND              VIA        MD0160PA00X+031740Y+022694               S0      
317GND              VIA        MD0160PA00X+031740Y+024694               S0      
317GND              VIA        MD0160PA00X+031740Y+026694               S0      
317GND              VIA        MD0160PA00X+031740Y+028694               S0      
317GND              VIA        MD0160PA00X+031990Y+046544               S0      
317GND              VIA        MD0160PA00X+033533Y+033796               S0      
317GND              VIA        MD0160PA00X+033533Y+035796               S0      
317GND              VIA        MD0160PA00X+033533Y+037796               S0      
317GND              VIA        MD0160PA00X+033533Y+041796               S0      
317GND              VIA        MD0160PA00X+033583Y+044246               S0      
317GND              VIA        MD0160PA00X+033642Y+002648               S0      
317GND              VIA        MD0160PA00X+033642Y+004648               S0      
317GND              VIA        MD0160PA00X+033642Y+000648               S0      
317GND              VIA        MD0160PA00X+033740Y+020644               S0      
317GND              VIA        MD0160PA00X+033740Y+022694               S0      
317GND              VIA        MD0160PA00X+033740Y+024694               S0      
317GND              VIA        MD0160PA00X+033740Y+026694               S0      
317GND              VIA        MD0160PA00X+033740Y+028694               S0      
317GND              VIA        MD0160PA00X+003399Y+036293               S0      
317GND              VIA        MD0160PA00X+033990Y+046544               S0      
317GND              VIA        MD0160PA00X+003490Y+034494               S0      
317GND              VIA        MD0160PA00X+035533Y+033796               S0      
317GND              VIA        MD0160PA00X+035533Y+035796               S0      
317GND              VIA        MD0160PA00X+035533Y+037796               S0      
317GND              VIA        MD0160PA00X+035533Y+041796               S0      
317GND              VIA        MD0160PA00X+035583Y+044246               S0      
317GND              VIA        MD0160PA00X+035642Y+002648               S0      
317GND              VIA        MD0160PA00X+035642Y+004648               S0      
317GND              VIA        MD0160PA00X+035642Y+000648               S0      
317GND              VIA        MD0160PA00X+035740Y+020644               S0      
317GND              VIA        MD0160PA00X+035740Y+022694               S0      
317GND              VIA        MD0160PA00X+035740Y+024694               S0      
317GND              VIA        MD0160PA00X+035740Y+026694               S0      
317GND              VIA        MD0160PA00X+035740Y+028694               S0      
317GND              VIA        MD0160PA00X+003583Y+044246               S0      
317GND              VIA        MD0160PA00X+035990Y+046544               S0      
317GND              VIA        MD0160PA00X+003642Y+002648               S0      
317GND              VIA        MD0160PA00X+003642Y+000648               S0      
317GND              VIA        MD0160PA00X+003677Y+022694               S0      
317GND              VIA        MD0160PA00X+003677Y+024694               S0      
317GND              VIA        MD0160PA00X+003740Y+020694               S0      
317GND              VIA        MD0160PA00X+003740Y+026694               S0      
317GND              VIA        MD0160PA00X+003740Y+028694               S0      
317GND              VIA        MD0160PA00X+037533Y+033796               S0      
317GND              VIA        MD0160PA00X+037533Y+035796               S0      
317GND              VIA        MD0160PA00X+037533Y+037796               S0      
317GND              VIA        MD0160PA00X+037533Y+041796               S0      
317GND              VIA        MD0160PA00X+037583Y+044246               S0      
317GND              VIA        MD0160PA00X+037642Y+002648               S0      
317GND              VIA        MD0160PA00X+037642Y+004648               S0      
317GND              VIA        MD0160PA00X+037642Y+000648               S0      
317GND              VIA        MD0160PA00X+037740Y+020644               S0      
317GND              VIA        MD0160PA00X+037740Y+022694               S0      
317GND              VIA        MD0160PA00X+037740Y+024694               S0      
317GND              VIA        MD0160PA00X+037740Y+026694               S0      
317GND              VIA        MD0160PA00X+037740Y+028694               S0      
317GND              VIA        MD0160PA00X+037990Y+046544               S0      
317GND              VIA        MD0160PA00X+039533Y+033796               S0      
317GND              VIA        MD0160PA00X+039533Y+035796               S0      
317GND              VIA        MD0160PA00X+039533Y+037796               S0      
317GND              VIA        MD0160PA00X+039533Y+041796               S0      
317GND              VIA        MD0160PA00X+039583Y+044246               S0      
317GND              VIA        MD0160PA00X+039642Y+002648               S0      
317GND              VIA        MD0160PA00X+039642Y+004648               S0      
317GND              VIA        MD0160PA00X+039642Y+000648               S0      
317GND              VIA        MD0160PA00X+039740Y+020644               S0      
317GND              VIA        MD0160PA00X+039740Y+022694               S0      
317GND              VIA        MD0160PA00X+039740Y+024694               S0      
317GND              VIA        MD0160PA00X+039740Y+026694               S0      
317GND              VIA        MD0160PA00X+039740Y+028694               S0      
317GND              VIA        MD0160PA00X+003990Y+046544               S0      
317GND              VIA        MD0160PA00X+039990Y+046544               S0      
317GND              VIA        MD0160PA00X+041533Y+033796               S0      
317GND              VIA        MD0160PA00X+041533Y+035796               S0      
317GND              VIA        MD0160PA00X+041533Y+037796               S0      
317GND              VIA        MD0160PA00X+041533Y+041796               S0      
317GND              VIA        MD0160PA00X+041583Y+044246               S0      
317GND              VIA        MD0160PA00X+041642Y+002648               S0      
317GND              VIA        MD0160PA00X+041642Y+004648               S0      
317GND              VIA        MD0160PA00X+041642Y+000648               S0      
317GND              VIA        MD0160PA00X+041740Y+020644               S0      
317GND              VIA        MD0160PA00X+041740Y+022694               S0      
317GND              VIA        MD0160PA00X+041740Y+024694               S0      
317GND              VIA        MD0160PA00X+041830Y+019750               S0      
317GND              VIA        MD0160PA00X+041830Y+020170               S0      
317GND              VIA        MD0160PA00X+041840Y+026694               S0      
317GND              VIA        MD0160PA00X+041840Y+028694               S0      
317GND              VIA        MD0160PA00X+041990Y+046544               S0      
317GND              VIA        MD0160PA00X+042250Y+019750               S0      
317GND              VIA        MD0160PA00X+042250Y+020170               S0      
317GND              VIA        MD0160PA00X+042670Y+019750               S0      
317GND              VIA        MD0160PA00X+042670Y+020170               S0      
317GND              VIA        MD0160PA00X+043130Y+019750               S0      
317GND              VIA        MD0160PA00X+043130Y+020170               S0      
317GND              VIA        MD0160PA00X+043533Y+041796               S0      
317GND              VIA        MD0160PA00X+043540Y+033844               S0      
317GND              VIA        MD0160PA00X+043540Y+035844               S0      
317GND              VIA        MD0160PA00X+043540Y+037844               S0      
317GND              VIA        MD0160PA00X+043550Y+019750               S0      
317GND              VIA        MD0160PA00X+043550Y+020170               S0      
317GND              VIA        MD0160PA00X+043583Y+044246               S0      
317GND              VIA        MD0160PA00X+043642Y+004648               S0      
317GND              VIA        MD0160PA00X+043642Y+000648               S0      
317GND              VIA        MD0160PA00X+043740Y+020644               S0      
317GND              VIA        MD0160PA00X+043740Y+022694               S0      
317GND              VIA        MD0160PA00X+043740Y+024694               S0      
317GND              VIA        MD0160PA00X+043740Y+026694               S0      
317GND              VIA        MD0160PA00X+043740Y+028694               S0      
317GND              VIA        MD0160PA00X+043970Y+019750               S0      
317GND              VIA        MD0160PA00X+043970Y+020170               S0      
317GND              VIA        MD0160PA00X+043990Y+046544               S0      
317GND              VIA        MD0160PA00X+044480Y+019750               S0      
317GND              VIA        MD0160PA00X+044480Y+020170               S0      
317GND              VIA        MD0160PA00X+044900Y+019750               S0      
317GND              VIA        MD0160PA00X+044900Y+020170               S0      
317GND              VIA        MD0160PA00X+045320Y+019750               S0      
317GND              VIA        MD0160PA00X+045320Y+020170               S0      
317GND              VIA        MD0160PA00X+045533Y+041796               S0      
317GND              VIA        MD0160PA00X+045540Y+033844               S0      
317GND              VIA        MD0160PA00X+045540Y+035844               S0      
317GND              VIA        MD0160PA00X+045540Y+037844               S0      
317GND              VIA        MD0160PA00X+045583Y+044246               S0      
317GND              VIA        MD0160PA00X+045642Y+004648               S0      
317GND              VIA        MD0160PA00X+045740Y+020644               S0      
317GND              VIA        MD0160PA00X+045740Y+022694               S0      
317GND              VIA        MD0160PA00X+045740Y+024694               S0      
317GND              VIA        MD0160PA00X+045740Y+026694               S0      
317GND              VIA        MD0160PA00X+045740Y+028694               S0      
317GND              VIA        MD0160PA00X+045780Y+019750               S0      
317GND              VIA        MD0160PA00X+045780Y+020170               S0      
317GND              VIA        MD0160PA00X+045990Y+046544               S0      
317GND              VIA        MD0160PA00X+046200Y+019750               S0      
317GND              VIA        MD0160PA00X+046200Y+020170               S0      
317GND              VIA        MD0160PA00X+046620Y+019750               S0      
317GND              VIA        MD0160PA00X+046620Y+020170               S0      
317GND              VIA        MD0160PA00X+047289Y+019697               S0      
317GND              VIA        MD0160PA00X+047289Y+020117               S0      
317GND              VIA        MD0160PA00X+047540Y+033844               S0      
317GND              VIA        MD0160PA00X+047540Y+035844               S0      
317GND              VIA        MD0160PA00X+047540Y+037844               S0      
317GND              VIA        MD0160PA00X+047642Y+004648               S0      
317GND              VIA        MD0160PA00X+047700Y+041800               S0      
317GND              VIA        MD0160PA00X+047709Y+019697               S0      
317GND              VIA        MD0160PA00X+047709Y+020117               S0      
317GND              VIA        MD0160PA00X+047740Y+022694               S0      
317GND              VIA        MD0160PA00X+047740Y+024694               S0      
317GND              VIA        MD0160PA00X+047740Y+026694               S0      
317GND              VIA        MD0160PA00X+047990Y+046544               S0      
317GND              VIA        MD0160PA00X+048031Y+020660               S0      
317GND              VIA        MD0160PA00X+048031Y+021080               S0      
317GND              VIA        MD0160PA00X+048451Y+020660               S0      
317GND              VIA        MD0160PA00X+048451Y+021080               S0      
317GND              VIA        MD0160PA00X+048551Y+044262               S0      
317GND              VIA        MD0160PA00X+048871Y+020660               S0      
317GND              VIA        MD0160PA00X+048871Y+021080               S0      
317GND              VIA        MD0160PA00X+049200Y+032100               S0      
317GND              VIA        MD0160PA00X+049291Y+020660               S0      
317GND              VIA        MD0160PA00X+049291Y+021080               S0      
317GND              VIA        MD0160PA00X+049540Y+033844               S0      
317GND              VIA        MD0160PA00X+049540Y+035844               S0      
317GND              VIA        MD0160PA00X+049540Y+037844               S0      
317GND              VIA        MD0160PA00X+049642Y+004648               S0      
317GND              VIA        MD0160PA00X+049740Y+022694               S0      
317GND              VIA        MD0160PA00X+049740Y+024694               S0      
317GND              VIA        MD0160PA00X+049805Y+019619               S0      
317GND              VIA        MD0160PA00X+049805Y+020039               S0      
317GND              VIA        MD0160PA00X+049900Y+041850               S0      
317GND              VIA        MD0160PA00X+049990Y+046544               S0      
317GND              VIA        MD0160PA00X+050225Y+019619               S0      
317GND              VIA        MD0160PA00X+050225Y+020039               S0      
317GND              VIA        MD0160PA00X+050551Y+044262               S0      
317GND              VIA        MD0160PA00X+050614Y+020636               S0      
317GND              VIA        MD0160PA00X+050614Y+021056               S0      
317GND              VIA        MD0160PA00X+050650Y+030550               S0      
317GND              VIA        MD0160PA00X+051034Y+020636               S0      
317GND              VIA        MD0160PA00X+051034Y+021056               S0      
317GND              VIA        MD0160PA00X+051250Y+032300               S0      
317GND              VIA        MD0160PA00X+051454Y+020636               S0      
317GND              VIA        MD0160PA00X+051454Y+021056               S0      
317GND              VIA        MD0160PA00X+051642Y+004648               S0      
317GND              VIA        MD0160PA00X+051642Y+000648               S0      
317GND              VIA        MD0160PA00X+051874Y+020636               S0      
317GND              VIA        MD0160PA00X+051874Y+021056               S0      
317GND              VIA        MD0160PA00X+051990Y+046544               S0      
317GND              VIA        MD0160PA00X+052038Y+030076               S0      
317GND              VIA        MD0160PA00X+052090Y+022844               S0      
317GND              VIA        MD0160PA00X+052356Y+019643               S0      
317GND              VIA        MD0160PA00X+052356Y+020063               S0      
317GND              VIA        MD0160PA00X+052516Y+031100               S0      
317GND              VIA        MD0160PA00X+052776Y+019643               S0      
317GND              VIA        MD0160PA00X+052776Y+020063               S0      
317GND              VIA        MD0160PA00X+053188Y+020619               S0      
317GND              VIA        MD0160PA00X+053188Y+021039               S0      
317GND              VIA        MD0160PA00X+053362Y+002648               S0      
317GND              VIA        MD0160PA00X+053362Y+004648               S0      
317GND              VIA        MD0160PA00X+053362Y+000648               S0      
317GND              VIA        MD0160PA00X+053400Y+028200               S0      
317GND              VIA        MD0160PA00X+053608Y+020619               S0      
317GND              VIA        MD0160PA00X+053608Y+021039               S0      
317GND              VIA        MD0160PA00X+053714Y+032640               S0      
317GND              VIA        MD0160PA00X+054028Y+020619               S0      
317GND              VIA        MD0160PA00X+054028Y+021039               S0      
317GND              VIA        MD0160PA00X+054090Y+022844               S0      
317GND              VIA        MD0160PA00X+054448Y+020619               S0      
317GND              VIA        MD0160PA00X+054448Y+021039               S0      
317GND              VIA        MD0160PA00X+054660Y+025797               S0      
317GND              VIA        MD0160PA00X+054897Y+019668               S0      
317GND              VIA        MD0160PA00X+054897Y+020088               S0      
317GND              VIA        MD0160PA00X+054950Y+030550               S0      
317GND              VIA        MD0160PA00X+055082Y+002648               S0      
317GND              VIA        MD0160PA00X+055082Y+004648               S0      
317GND              VIA        MD0160PA00X+055082Y+000648               S0      
317GND              VIA        MD0160PA00X+055317Y+019668               S0      
317GND              VIA        MD0160PA00X+055317Y+020088               S0      
317GND              VIA        MD0160PA00X+005550Y+041700               S0      
317GND              VIA        MD0160PA00X+055642Y+006648               S0      
317GND              VIA        MD0160PA00X+056000Y+028297               S0      
317GND              VIA        MD0160PA00X+056050Y+026800               S0      
317GND              VIA        MD0160PA00X+056150Y+029800               S0      
317GND              VIA        MD0160PA00X+005642Y+004648               S0      
317GND              VIA        MD0160PA00X+056802Y+002648               S0      
317GND              VIA        MD0160PA00X+056802Y+004648               S0      
317GND              VIA        MD0160PA00X+056802Y+000648               S0      
317GND              VIA        MD0160PA00X+005740Y+020694               S0      
317GND              VIA        MD0160PA00X+005740Y+022694               S0      
317GND              VIA        MD0160PA00X+005740Y+024694               S0      
317GND              VIA        MD0160PA00X+005740Y+026694               S0      
317GND              VIA        MD0160PA00X+005740Y+028694               S0      
317GND              VIA        MD0160PA00X+057362Y+006697               S0      
317GND              VIA        MD0160PA00X+057750Y+030500               S0      
317GND              VIA        MD0160PA00X+058454Y+008667               S0      
317GND              VIA        MD0160PA00X+058522Y+002648               S0      
317GND              VIA        MD0160PA00X+058522Y+004648               S0      
317GND              VIA        MD0160PA00X+058522Y+000648               S0      
317GND              VIA        MD0160PA00X+058750Y+031850               S0      
317GND              VIA        MD0160PA00X+059450Y+011700               S0      
317GND              VIA        MD0160PA00X+060000Y+029850               S0      
317GND              VIA        MD0160PA00X+060242Y+002648               S0      
317GND              VIA        MD0160PA00X+060242Y+004648               S0      
317GND              VIA        MD0160PA00X+060242Y+000648               S0      
317GND              VIA        MD0160PA00X+060700Y+012350               S0      
317GND              VIA        MD0160PA00X+061090Y+042544               S0      
317GND              VIA        MD0160PA00X+061090Y+044544               S0      
317GND              VIA        MD0160PA00X+061090Y+046544               S0      
317GND              VIA        MD0160PA00X+061125Y+006570               S0      
317GND              VIA        MD0160PA00X+061140Y+008694               S0      
317GND              VIA        MD0160PA00X+061540Y+026644               S0      
317GND              VIA        MD0160PA00X+061540Y+028444               S0      
317GND              VIA        MD0160PA00X+061550Y+019900               S0      
317GND              VIA        MD0160PA00X+061590Y+022444               S0      
317GND              VIA        MD0160PA00X+061590Y+024444               S0      
317GND              VIA        MD0160PA00X+061600Y+011550               S0      
317GND              VIA        MD0160PA00X+061600Y+013800               S0      
317GND              VIA        MD0160PA00X+061600Y+017350               S0      
317GND              VIA        MD0160PA00X+061650Y+031624               S0      
317GND              VIA        MD0160PA00X+006190Y+035894               S0      
317GND              VIA        MD0160PA00X+061962Y+002648               S0      
317GND              VIA        MD0160PA00X+061962Y+004648               S0      
317GND              VIA        MD0160PA00X+061962Y+000648               S0      
317GND              VIA        MD0160PA00X+006200Y+044250               S0      
317GND              VIA        MD0160PA00X+006240Y+033844               S0      
317GND              VIA        MD0160PA00X+062650Y+007850               S0      
317GND              VIA        MD0160PA00X+062850Y+010400               S0      
317GND              VIA        MD0160PA00X+000640Y+036994               S0      
317GND              VIA        MD0160PA00X+063000Y+034550               S0      
317GND              VIA        MD0160PA00X+063000Y+038750               S0      
317GND              VIA        MD0160PA00X+063290Y+040494               S0      
317GND              VIA        MD0160PA00X+063290Y+042494               S0      
317GND              VIA        MD0160PA00X+063290Y+044494               S0      
317GND              VIA        MD0160PA00X+063290Y+046494               S0      
317GND              VIA        MD0160PA00X+063340Y+032544               S0      
317GND              VIA        MD0160PA00X+063375Y+006570               S0      
317GND              VIA        MD0160PA00X+063390Y+008694               S0      
317GND              VIA        MD0160PA00X+063400Y+012350               S0      
317GND              VIA        MD0160PA00X+063412Y+002648               S0      
317GND              VIA        MD0160PA00X+063412Y+004648               S0      
317GND              VIA        MD0160PA00X+063412Y+000648               S0      
317GND              VIA        MD0160PA00X+006440Y+030444               S0      
317GND              VIA        MD0160PA00X+006783Y+046546               S0      
317GND              VIA        MD0160PA00X+000690Y+038744               S0      
317GND              VIA        MD0160PA00X+000690Y+044544               S0      
317GND              VIA        MD0160PA00X+000690Y+046544               S0      
317GND              VIA        MD0160PA00X+000740Y+020694               S0      
317GND              VIA        MD0160PA00X+000740Y+021694               S0      
317GND              VIA        MD0160PA00X+000740Y+022694               S0      
317GND              VIA        MD0160PA00X+000740Y+023694               S0      
317GND              VIA        MD0160PA00X+000740Y+024694               S0      
317GND              VIA        MD0160PA00X+000740Y+025694               S0      
317GND              VIA        MD0160PA00X+000740Y+026694               S0      
317GND              VIA        MD0160PA00X+000740Y+027694               S0      
317GND              VIA        MD0160PA00X+000740Y+028694               S0      
317GND              VIA        MD0160PA00X+007550Y+041750               S0      
317GND              VIA        MD0160PA00X+007642Y+004648               S0      
317GND              VIA        MD0160PA00X+007740Y+020694               S0      
317GND              VIA        MD0160PA00X+007740Y+022694               S0      
317GND              VIA        MD0160PA00X+007740Y+024694               S0      
317GND              VIA        MD0160PA00X+007740Y+026694               S0      
317GND              VIA        MD0160PA00X+007740Y+028694               S0      
317GND              VIA        MD0160PA00X+007790Y+033844               S0      
317GND              VIA        MD0160PA00X+007840Y+035844               S0      
317GND              VIA        MD0160PA00X+008533Y+044296               S0      
317GND              VIA        MD0160PA00X+008640Y+030394               S0      
317GND              VIA        MD0160PA00X+009150Y+046550               S0      
317GND              VIA        MD0160PA00X+009533Y+035796               S0      
317GND              VIA        MD0160PA00X+009533Y+037796               S0      
317GND              VIA        MD0160PA00X+009533Y+041796               S0      
317GND              VIA        MD0160PA00X+009640Y+033794               S0      
317GND              VIA        MD0160PA00X+009642Y+004648               S0      
317GND              VIA        MD0160PA00X+009740Y+020694               S0      
317GND              VIA        MD0160PA00X+009740Y+022694               S0      
317GND              VIA        MD0160PA00X+009740Y+024694               S0      
317GND              VIA        MD0160PA00X+009740Y+026694               S0      
317GND              VIA        MD0160PA00X+009740Y+028694               S0      
327P12V                               A01X+047290Y+018264X0550Y0450     S0      
327P12V                               A01X+000020Y+018982X0550Y0450     S0      
327P12V                               A01X+000930Y+018982X0550Y0450     S0      
327P12V                               A01X+048763Y+017329X0950Y0900     S0      
327P12V                               A01X+051299Y+017336X0950Y0900     S0      
327P12V                               A01X+053814Y+017338X0950Y0900     S0      
317P12V                         D0340PA01X+061800Y+007730               S0      
317P12V                         D0410PA00X+060071Y+016189               S0      
317P12V                         D0410PA00X+059071Y+016189               S0      
317P12V                         D0410PA00X+058071Y+016189               S0      
317P12V                         D0410PA00X+057071Y+016189               S0      
317P12V                         D0410PA00X+060071Y+017189               S0      
317P12V                         D0410PA00X+059071Y+017189               S0      
317P12V                         D0410PA00X+058071Y+017189               S0      
317P12V                         D0410PA00X+057071Y+017189               S0      
317P12V                         D0410PA00X+060071Y+018189               S0      
317P12V                         D0410PA00X+059071Y+018189               S0      
317P12V                         D0410PA00X+058071Y+018189               S0      
317P12V                         D0410PA00X+057071Y+018189               S0      
317P12V                         D0410PA00X+060071Y+019189               S0      
317P12V                         D0410PA00X+059071Y+019189               S0      
317P12V                         D0410PA00X+058071Y+019189               S0      
317P12V                         D0410PA00X+057071Y+019189               S0      
327P12V                               A04X-002501Y+013342X2480Y3720     S0      
327P12V                               A04X-002201Y+014272X0010Y0010     S0      
327P12V                               A04X-002201Y+013342X0010Y0010     S0      
327P12V                               A04X-002201Y+012412X0010Y0010     S0      
327P12V                               A04X-002501Y+017342X2480Y3720     S0      
327P12V                               A04X-002201Y+018272X0010Y0010     S0      
327P12V                               A04X-002201Y+017342X0010Y0010     S0      
327P12V                               A04X-002201Y+016412X0010Y0010     S0      
327P12V                               A01X-002501Y+017342X2480Y3720     S0      
327P12V                               A01X-002651Y+018272X0010Y0010     S0      
327P12V                               A01X-002651Y+017342X0010Y0010     S0      
327P12V                               A01X-002651Y+016412X0010Y0010     S0      
327P12V                               A01X-002501Y+013342X2480Y3720     S0      
327P12V                               A01X-002651Y+014272X0010Y0010     S0      
327P12V                               A01X-002651Y+013342X0010Y0010     S0      
327P12V                               A01X-002651Y+012412X0010Y0010     S0      
327P12V                               A01X+042150Y+018070X1100Y0550     S0      
327P12V                               A01X+043500Y+018070X1100Y0550     S0      
327P12V                               A01X+044850Y+018070X1100Y0550     S0      
327P12V                               A01X+046200Y+018070X1100Y0550     S0      
317P12V             VIA        MD0280PA04X+018940Y+011594               S0      
317P12V             VIA        MD0280PA04X+034790Y+011744               S0      
317P12V             VIA        MD0280PA04X+004690Y+011794               S0      
317P12V             VIA        MD0280PA04X+004690Y+015294               S0      
317P12V             VIA        MD0280PA04X+004690Y+018294               S0      
317P12V             VIA        MD0280PA04X+052640Y+011694               S0      
317P12V             VIA        MD0280PA04X+007300Y+009450               S0      
317P12V             VIA        MD0160PA00X-000335Y+011750               S0      
317P12V             VIA        MD0160PA00X-000358Y+012648               S0      
317P12V             VIA        MD0160PA00X-000358Y+013648               S0      
317P12V             VIA        MD0160PA00X-000358Y+014648               S0      
317P12V             VIA        MD0160PA00X-000358Y+015648               S0      
317P12V             VIA        MD0160PA00X-000358Y+016648               S0      
317P12V             VIA        MD0160PA00X-000358Y+017648               S0      
317P12V             VIA        MD0160PA00X+011642Y+010648               S0      
317P12V             VIA        MD0160PA00X+011642Y+012648               S0      
317P12V             VIA        MD0160PA00X+011642Y+014648               S0      
317P12V             VIA        MD0160PA00X+011642Y+016648               S0      
317P12V             VIA        MD0160PA00X+011642Y+018648               S0      
317P12V             VIA        MD0160PA00X+011642Y+006648               S0      
317P12V             VIA        MD0160PA00X+011642Y+008648               S0      
317P12V             VIA        MD0160PA00X+013642Y+010648               S0      
317P12V             VIA        MD0160PA00X+013642Y+012648               S0      
317P12V             VIA        MD0160PA00X+013642Y+014648               S0      
317P12V             VIA        MD0160PA00X+013642Y+016648               S0      
317P12V             VIA        MD0160PA00X+013642Y+018648               S0      
317P12V             VIA        MD0160PA00X+013642Y+006648               S0      
317P12V             VIA        MD0160PA00X+013642Y+008648               S0      
317P12V             VIA        MD0160PA00X+015642Y+010648               S0      
317P12V             VIA        MD0160PA00X+015642Y+012648               S0      
317P12V             VIA        MD0160PA00X+015642Y+014648               S0      
317P12V             VIA        MD0160PA00X+015642Y+016648               S0      
317P12V             VIA        MD0160PA00X+015642Y+018648               S0      
317P12V             VIA        MD0160PA00X+015642Y+006648               S0      
317P12V             VIA        MD0160PA00X+015642Y+008648               S0      
317P12V             VIA        MD0160PA00X+001642Y+010648               S0      
317P12V             VIA        MD0160PA00X+001642Y+011648               S0      
317P12V             VIA        MD0160PA00X+001642Y+012648               S0      
317P12V             VIA        MD0160PA00X+001642Y+013648               S0      
317P12V             VIA        MD0160PA00X+001642Y+014648               S0      
317P12V             VIA        MD0160PA00X+001642Y+015648               S0      
317P12V             VIA        MD0160PA00X+001642Y+016648               S0      
317P12V             VIA        MD0160PA00X+001642Y+017648               S0      
317P12V             VIA        MD0160PA00X+001642Y+018648               S0      
317P12V             VIA        MD0160PA00X+001642Y+008648               S0      
317P12V             VIA        MD0160PA00X+017642Y+010648               S0      
317P12V             VIA        MD0160PA00X+017642Y+012648               S0      
317P12V             VIA        MD0160PA00X+017642Y+014648               S0      
317P12V             VIA        MD0160PA00X+017642Y+016648               S0      
317P12V             VIA        MD0160PA00X+017642Y+018648               S0      
317P12V             VIA        MD0160PA00X+017642Y+006648               S0      
317P12V             VIA        MD0160PA00X+017642Y+008648               S0      
317P12V             VIA        MD0160PA00X+019642Y+010648               S0      
317P12V             VIA        MD0160PA00X+019642Y+012648               S0      
317P12V             VIA        MD0160PA00X+019642Y+014648               S0      
317P12V             VIA        MD0160PA00X+019642Y+016648               S0      
317P12V             VIA        MD0160PA00X+019642Y+018648               S0      
317P12V             VIA        MD0160PA00X+019642Y+006648               S0      
317P12V             VIA        MD0160PA00X+019642Y+008648               S0      
317P12V             VIA        MD0160PA00X+021642Y+010648               S0      
317P12V             VIA        MD0160PA00X+021642Y+012648               S0      
317P12V             VIA        MD0160PA00X+021642Y+014648               S0      
317P12V             VIA        MD0160PA00X+021642Y+016648               S0      
317P12V             VIA        MD0160PA00X+021642Y+018648               S0      
317P12V             VIA        MD0160PA00X+021642Y+006648               S0      
317P12V             VIA        MD0160PA00X+021642Y+008648               S0      
317P12V             VIA        MD0160PA00X+023642Y+010648               S0      
317P12V             VIA        MD0160PA00X+023642Y+012648               S0      
317P12V             VIA        MD0160PA00X+023642Y+014648               S0      
317P12V             VIA        MD0160PA00X+023642Y+016648               S0      
317P12V             VIA        MD0160PA00X+023642Y+018648               S0      
317P12V             VIA        MD0160PA00X+023642Y+006648               S0      
317P12V             VIA        MD0160PA00X+023642Y+008648               S0      
317P12V             VIA        MD0160PA00X+025150Y+016650               S0      
317P12V             VIA        MD0160PA00X+025642Y+010648               S0      
317P12V             VIA        MD0160PA00X+025642Y+012648               S0      
317P12V             VIA        MD0160PA00X+025642Y+014648               S0      
317P12V             VIA        MD0160PA00X+025642Y+018648               S0      
317P12V             VIA        MD0160PA00X+025642Y+006648               S0      
317P12V             VIA        MD0160PA00X+025642Y+008648               S0      
317P12V             VIA        MD0160PA00X+002642Y+011648               S0      
317P12V             VIA        MD0160PA00X+002642Y+012648               S0      
317P12V             VIA        MD0160PA00X+002642Y+013648               S0      
317P12V             VIA        MD0160PA00X+002642Y+014648               S0      
317P12V             VIA        MD0160PA00X+002642Y+015648               S0      
317P12V             VIA        MD0160PA00X+002642Y+016648               S0      
317P12V             VIA        MD0160PA00X+002642Y+017648               S0      
317P12V             VIA        MD0160PA00X+002642Y+018648               S0      
317P12V             VIA        MD0160PA00X+027350Y+006650               S0      
317P12V             VIA        MD0160PA00X+027450Y+010650               S0      
317P12V             VIA        MD0160PA00X+027450Y+008650               S0      
317P12V             VIA        MD0160PA00X+027550Y+018650               S0      
317P12V             VIA        MD0160PA00X+027642Y+012648               S0      
317P12V             VIA        MD0160PA00X+027642Y+014648               S0      
317P12V             VIA        MD0160PA00X+027642Y+016648               S0      
317P12V             VIA        MD0160PA00X+029550Y+016900               S0      
317P12V             VIA        MD0160PA00X+029642Y+012648               S0      
317P12V             VIA        MD0160PA00X+029642Y+014648               S0      
317P12V             VIA        MD0160PA00X+029642Y+018648               S0      
317P12V             VIA        MD0160PA00X+030000Y+010650               S0      
317P12V             VIA        MD0160PA00X+030100Y+008650               S0      
317P12V             VIA        MD0160PA00X+030200Y+006700               S0      
317P12V             VIA        MD0160PA00X+031642Y+010648               S0      
317P12V             VIA        MD0160PA00X+031642Y+012648               S0      
317P12V             VIA        MD0160PA00X+031642Y+014648               S0      
317P12V             VIA        MD0160PA00X+031642Y+006648               S0      
317P12V             VIA        MD0160PA00X+031642Y+008648               S0      
317P12V             VIA        MD0160PA00X+031700Y+016650               S0      
317P12V             VIA        MD0160PA00X+031750Y+018650               S0      
317P12V             VIA        MD0160PA00X+033642Y+010648               S0      
317P12V             VIA        MD0160PA00X+033642Y+012648               S0      
317P12V             VIA        MD0160PA00X+033642Y+014648               S0      
317P12V             VIA        MD0160PA00X+033642Y+018648               S0      
317P12V             VIA        MD0160PA00X+033642Y+006648               S0      
317P12V             VIA        MD0160PA00X+033642Y+008648               S0      
317P12V             VIA        MD0160PA00X+033850Y+016600               S0      
317P12V             VIA        MD0160PA00X+035450Y+016650               S0      
317P12V             VIA        MD0160PA00X+035642Y+010648               S0      
317P12V             VIA        MD0160PA00X+035642Y+012648               S0      
317P12V             VIA        MD0160PA00X+035642Y+014648               S0      
317P12V             VIA        MD0160PA00X+035642Y+006648               S0      
317P12V             VIA        MD0160PA00X+035642Y+008648               S0      
317P12V             VIA        MD0160PA00X+035750Y+018650               S0      
317P12V             VIA        MD0160PA00X+003642Y+010648               S0      
317P12V             VIA        MD0160PA00X+003642Y+012648               S0      
317P12V             VIA        MD0160PA00X+003642Y+014648               S0      
317P12V             VIA        MD0160PA00X+003642Y+016648               S0      
317P12V             VIA        MD0160PA00X+003642Y+018648               S0      
317P12V             VIA        MD0160PA00X+003642Y+008648               S0      
317P12V             VIA        MD0160PA00X+037642Y+010648               S0      
317P12V             VIA        MD0160PA00X+037642Y+012648               S0      
317P12V             VIA        MD0160PA00X+037642Y+014648               S0      
317P12V             VIA        MD0160PA00X+037642Y+018648               S0      
317P12V             VIA        MD0160PA00X+037642Y+006648               S0      
317P12V             VIA        MD0160PA00X+037642Y+008648               S0      
317P12V             VIA        MD0160PA00X+038000Y+016650               S0      
317P12V             VIA        MD0160PA00X+039642Y+010648               S0      
317P12V             VIA        MD0160PA00X+039642Y+012648               S0      
317P12V             VIA        MD0160PA00X+039642Y+014648               S0      
317P12V             VIA        MD0160PA00X+039642Y+016648               S0      
317P12V             VIA        MD0160PA00X+039642Y+018648               S0      
317P12V             VIA        MD0160PA00X+039642Y+006648               S0      
317P12V             VIA        MD0160PA00X+039642Y+008648               S0      
317P12V             VIA        MD0160PA00X+041642Y+010648               S0      
317P12V             VIA        MD0160PA00X+041642Y+012648               S0      
317P12V             VIA        MD0160PA00X+041642Y+014648               S0      
317P12V             VIA        MD0160PA00X+041642Y+006648               S0      
317P12V             VIA        MD0160PA00X+041642Y+008648               S0      
317P12V             VIA        MD0160PA00X+041650Y+016600               S0      
317P12V             VIA        MD0160PA00X+041752Y+017028               S0      
317P12V             VIA        MD0160PA00X+041752Y+017448               S0      
317P12V             VIA        MD0160PA00X+042172Y+017028               S0      
317P12V             VIA        MD0160PA00X+042172Y+017448               S0      
317P12V             VIA        MD0160PA00X+042592Y+017028               S0      
317P12V             VIA        MD0160PA00X+042592Y+017448               S0      
317P12V             VIA        MD0160PA00X+043110Y+017030               S0      
317P12V             VIA        MD0160PA00X+043110Y+017450               S0      
317P12V             VIA        MD0160PA00X+043530Y+017030               S0      
317P12V             VIA        MD0160PA00X+043530Y+017450               S0      
317P12V             VIA        MD0160PA00X+043642Y+010648               S0      
317P12V             VIA        MD0160PA00X+043642Y+012648               S0      
317P12V             VIA        MD0160PA00X+043642Y+014648               S0      
317P12V             VIA        MD0160PA00X+043642Y+006648               S0      
317P12V             VIA        MD0160PA00X+043642Y+008648               S0      
317P12V             VIA        MD0160PA00X+043650Y+016600               S0      
317P12V             VIA        MD0160PA00X+043950Y+017030               S0      
317P12V             VIA        MD0160PA00X+043950Y+017450               S0      
317P12V             VIA        MD0160PA00X+044410Y+017030               S0      
317P12V             VIA        MD0160PA00X+044410Y+017450               S0      
317P12V             VIA        MD0160PA00X+044830Y+017030               S0      
317P12V             VIA        MD0160PA00X+044830Y+017450               S0      
317P12V             VIA        MD0160PA00X+045250Y+017030               S0      
317P12V             VIA        MD0160PA00X+045250Y+017450               S0      
317P12V             VIA        MD0160PA00X+045642Y+010648               S0      
317P12V             VIA        MD0160PA00X+045642Y+012648               S0      
317P12V             VIA        MD0160PA00X+045642Y+014648               S0      
317P12V             VIA        MD0160PA00X+045642Y+006648               S0      
317P12V             VIA        MD0160PA00X+045642Y+008648               S0      
317P12V             VIA        MD0160PA00X+045650Y+016650               S0      
317P12V             VIA        MD0160PA00X+045710Y+017080               S0      
317P12V             VIA        MD0160PA00X+045710Y+017500               S0      
317P12V             VIA        MD0160PA00X+046130Y+017080               S0      
317P12V             VIA        MD0160PA00X+046130Y+017500               S0      
317P12V             VIA        MD0160PA00X+046550Y+017080               S0      
317P12V             VIA        MD0160PA00X+046550Y+017500               S0      
317P12V             VIA        MD0160PA00X+047308Y+017039               S0      
317P12V             VIA        MD0160PA00X+047308Y+017459               S0      
317P12V             VIA        MD0160PA00X+047642Y+010648               S0      
317P12V             VIA        MD0160PA00X+047642Y+012648               S0      
317P12V             VIA        MD0160PA00X+047642Y+014648               S0      
317P12V             VIA        MD0160PA00X+047642Y+006648               S0      
317P12V             VIA        MD0160PA00X+047642Y+008648               S0      
317P12V             VIA        MD0160PA00X+047728Y+017039               S0      
317P12V             VIA        MD0160PA00X+047728Y+017459               S0      
317P12V             VIA        MD0160PA00X+048124Y+016067               S0      
317P12V             VIA        MD0160PA00X+048124Y+016487               S0      
317P12V             VIA        MD0160PA00X+048544Y+016067               S0      
317P12V             VIA        MD0160PA00X+048544Y+016487               S0      
317P12V             VIA        MD0160PA00X+048964Y+016067               S0      
317P12V             VIA        MD0160PA00X+048964Y+016487               S0      
317P12V             VIA        MD0160PA00X+049384Y+016067               S0      
317P12V             VIA        MD0160PA00X+049384Y+016487               S0      
317P12V             VIA        MD0160PA00X+049642Y+010648               S0      
317P12V             VIA        MD0160PA00X+049642Y+012648               S0      
317P12V             VIA        MD0160PA00X+049642Y+014648               S0      
317P12V             VIA        MD0160PA00X+049642Y+006648               S0      
317P12V             VIA        MD0160PA00X+049642Y+008648               S0      
317P12V             VIA        MD0160PA00X+049840Y+017049               S0      
317P12V             VIA        MD0160PA00X+049840Y+017469               S0      
317P12V             VIA        MD0160PA00X+050260Y+017049               S0      
317P12V             VIA        MD0160PA00X+050260Y+017469               S0      
317P12V             VIA        MD0160PA00X+050662Y+016091               S0      
317P12V             VIA        MD0160PA00X+050662Y+016511               S0      
317P12V             VIA        MD0160PA00X+051082Y+016091               S0      
317P12V             VIA        MD0160PA00X+051082Y+016511               S0      
317P12V             VIA        MD0160PA00X+051502Y+016091               S0      
317P12V             VIA        MD0160PA00X+051502Y+016511               S0      
317P12V             VIA        MD0160PA00X+051642Y+010648               S0      
317P12V             VIA        MD0160PA00X+051642Y+012648               S0      
317P12V             VIA        MD0160PA00X+051642Y+014648               S0      
317P12V             VIA        MD0160PA00X+051642Y+006648               S0      
317P12V             VIA        MD0160PA00X+051642Y+008648               S0      
317P12V             VIA        MD0160PA00X+051922Y+016091               S0      
317P12V             VIA        MD0160PA00X+051922Y+016511               S0      
317P12V             VIA        MD0160PA00X+052351Y+017097               S0      
317P12V             VIA        MD0160PA00X+052351Y+017517               S0      
317P12V             VIA        MD0160PA00X+052771Y+017097               S0      
317P12V             VIA        MD0160PA00X+052771Y+017517               S0      
317P12V             VIA        MD0160PA00X+053188Y+016132               S0      
317P12V             VIA        MD0160PA00X+053188Y+016552               S0      
317P12V             VIA        MD0160PA00X+053608Y+016132               S0      
317P12V             VIA        MD0160PA00X+053608Y+016552               S0      
317P12V             VIA        MD0160PA00X+053642Y+010648               S0      
317P12V             VIA        MD0160PA00X+053642Y+012648               S0      
317P12V             VIA        MD0160PA00X+053642Y+014648               S0      
317P12V             VIA        MD0160PA00X+053642Y+006648               S0      
317P12V             VIA        MD0160PA00X+053642Y+008648               S0      
317P12V             VIA        MD0160PA00X+054028Y+016132               S0      
317P12V             VIA        MD0160PA00X+054028Y+016552               S0      
317P12V             VIA        MD0160PA00X+054448Y+016132               S0      
317P12V             VIA        MD0160PA00X+054448Y+016552               S0      
317P12V             VIA        MD0160PA00X+054872Y+017092               S0      
317P12V             VIA        MD0160PA00X+054872Y+017512               S0      
317P12V             VIA        MD0160PA00X+055292Y+017092               S0      
317P12V             VIA        MD0160PA00X+055292Y+017512               S0      
317P12V             VIA        MD0160PA00X+055642Y+010648               S0      
317P12V             VIA        MD0160PA00X+055642Y+012648               S0      
317P12V             VIA        MD0160PA00X+055642Y+014648               S0      
317P12V             VIA        MD0160PA00X+055642Y+008648               S0      
317P12V             VIA        MD0160PA00X+005642Y+010648               S0      
317P12V             VIA        MD0160PA00X+005642Y+012648               S0      
317P12V             VIA        MD0160PA00X+005642Y+014648               S0      
317P12V             VIA        MD0160PA00X+005642Y+016648               S0      
317P12V             VIA        MD0160PA00X+005642Y+018648               S0      
317P12V             VIA        MD0160PA00X+005642Y+006648               S0      
317P12V             VIA        MD0160PA00X+005642Y+008648               S0      
317P12V             VIA        MD0160PA00X+057642Y+010648               S0      
317P12V             VIA        MD0160PA00X+057642Y+012648               S0      
317P12V             VIA        MD0160PA00X+000642Y+011648               S0      
317P12V             VIA        MD0160PA00X+000642Y+012648               S0      
317P12V             VIA        MD0160PA00X+000642Y+013648               S0      
317P12V             VIA        MD0160PA00X+000642Y+014648               S0      
317P12V             VIA        MD0160PA00X+000642Y+015648               S0      
317P12V             VIA        MD0160PA00X+000642Y+016648               S0      
317P12V             VIA        MD0160PA00X+000642Y+017648               S0      
317P12V             VIA        MD0160PA00X+007642Y+010648               S0      
317P12V             VIA        MD0160PA00X+007642Y+012648               S0      
317P12V             VIA        MD0160PA00X+007642Y+014648               S0      
317P12V             VIA        MD0160PA00X+007642Y+016648               S0      
317P12V             VIA        MD0160PA00X+007642Y+018648               S0      
317P12V             VIA        MD0160PA00X+007642Y+006648               S0      
317P12V             VIA        MD0160PA00X+007642Y+008648               S0      
317P12V             VIA        MD0160PA00X+009642Y+010648               S0      
317P12V             VIA        MD0160PA00X+009642Y+012648               S0      
317P12V             VIA        MD0160PA00X+009642Y+014648               S0      
317P12V             VIA        MD0160PA00X+009642Y+016648               S0      
317P12V             VIA        MD0160PA00X+009642Y+018648               S0      
317P12V             VIA        MD0160PA00X+009642Y+006648               S0      
317P12V             VIA        MD0160PA00X+009642Y+008648               S0      
317I2C_C_SDA                    D0340PA01X+003813Y+037433               S0      
317I2C_C_SDA                    D0220PA01X+006615Y+037398               S0      
317I2C_C_SDA                    D0220PA01X+004316Y+037389               S0      
317I2C_C_SDA                    D0220PA01X+003351Y+037413               S0      
317I2C_C_SDA        VIA        MD0280PA01X+002818Y+037900               S0      
317I2C_C_SCL                    D0340PA01X+003811Y+036873               S0      
317I2C_C_SCL                    D0220PA01X+006610Y+036947               S0      
317I2C_C_SCL                    D0220PA01X+004307Y+036925               S0      
317I2C_C_SCL                    D0220PA01X+003351Y+036893               S0      
317I2C_C_SCL        VIA        MD0280PA01X+002818Y+036406               S0      
317NNAME00000                   D0340PA01X+054250Y+026377               S0      
317NNAME00000                   D0220PA01X+053773Y+026397               S0      
317NNAME00000                   D0410PA00X+060071Y+022441               S0      
317NNAME00000       VIA        MD0280PA01X+054842Y+026297               S0      
317NNAME00001                   D0340PA01X+054250Y+026917               S0      
317NNAME00001                   D0220PA01X+053773Y+026897               S0      
317NNAME00001                   D0410PA00X+060071Y+020441               S0      
317NNAME00001       VIA        MD0280PA01X+054842Y+026977               S0      
317PWM_EXP_B_OUT                D0220PA01X+003860Y+033794               S0      
317PWM_EXP_B_OUT                D0410PA00X+060071Y+024441               S0      
317PWM_EXP_B_OUT    VIA        MD0280PA01X+043959Y+032162               S0      
317PWM_EXP_A_OUT                D0220PA01X+003860Y+033344               S0      
317PWM_EXP_A_OUT                D0410PA00X+059071Y+021441               S0      
317PWM_EXP_A_OUT    VIA        MD0280PA01X+017676Y+031944               S0      
317SELF_1B&2B_HB                D0410PA00X+059071Y+023441               S0      
327SELF_1B&2B_HB                      A01X-002756Y+034720X1970Y0320     S0      
317SELF_1B&2B_HB    VIA        MD0280PA01X+022872Y+031509               S0      
317TPS2490_EN1                  D0220PA01X+058300Y+008020               S0      
317TPS2490_EN1                  D0370PA00X+059610Y+008268               S0      
317TPS2490_EN1                  D0410PA00X+058071Y+020441               S0      
317TPS2490_EN1      VIA        MD0280PA04X+061000Y+010000               S0      
317TPS2490_EN2                  D0220PA01X+058300Y+007680               S0      
317TPS2490_EN2                  D0370PA00X+060201Y+007480               S0      
317TPS2490_EN2                  D0410PA00X+058071Y+021441               S0      
317TPS2490_EN2      VIA        MD0280PA04X+061275Y+009302               S0      
317SELF_1A&2A_HB                D0410PA00X+058071Y+022441               S0      
327SELF_1A&2A_HB                      A01X-002756Y+035220X1970Y0320     S0      
317SELF_1A&2A_HB    VIA        MD0280PA01X+026468Y+031727               S0      
317PEER_1A&2A_HB                D0410PA00X+058071Y+023441               S0      
327PEER_1A&2A_HB                      A01X-002756Y+032220X1970Y0320     S0      
317PEER_1A&2A_HB    VIA        MD0280PA01X+019629Y+030204               S0      
317PEER_1A&2A_HB    VIA        MD0160PA00X+056150Y+023200               S0      
317PEER_1B&2B_HB                D0410PA00X+058071Y+024441               S0      
327PEER_1B&2B_HB                      A01X-002756Y+031720X1970Y0320     S0      
317PEER_1B&2B_HB    VIA        MD0280PA01X+046326Y+029987               S0      
317PEER_1B&2B_HB    VIA        MD0160PA00X+055700Y+023150               S0      
317NNAME00002                   D0410PA00X+057071Y+020441               S0      
327NNAME00002                         A04X-002756Y+031720X1970Y0320     S0      
317NNAME00002       VIA        MD0280PA01X+013506Y+030422               S0      
317NNAME00002       VIA        MD0160PA00X+000340Y+032694               S0      
317TRAY_ID                      D0410PA00X+057071Y+021441               S0      
327TRAY_ID                            A01X-002756Y+034220X1970Y0320     S0      
317TRAY_ID          VIA        MD0280PA01X+031099Y+031074               S0      
317FCB_HW_REV                   D0410PA00X+057071Y+022441               S0      
327FCB_HW_REV                         A01X-002756Y+033720X1970Y0320     S0      
317FCB_HW_REV       VIA        MD0280PA01X+043941Y+030857               S0      
317NNAME00003                   D0410PA00X+057071Y+023441               S0      
327NNAME00003                         A01X-002756Y+033220X1970Y0320     S0      
317NNAME00003       VIA        MD0280PA01X+040156Y+030639               S0      
317NNAME00004                   D0220PA01X+053800Y+029330               S0      
317NNAME00004                   D0300PA01X+052901Y+029326               S0      
317NNAME00004                   D0410PA00X+057071Y+024441               S0      
327NNAME00004                         A04X-002756Y+032720X1970Y0320     S0      
317NNAME00004       VIA        MD0280PA01X+035809Y+031292               S0      
317NNAME00004       VIA        MD0160PA00X+001000Y+033200               S0      
317PWM_EXP_B                    D0220PA01X+003520Y+033794               S0      
327PWM_EXP_B                          A04X-002756Y+032220X1970Y0320     S0      
317PWM_EXP_B        VIA        MD0280PA04X+002650Y+033044               S0      
317PWM_EXP_B        VIA        MD0160PA00X+003092Y+033567               S0      
317PWM_EXP_A                    D0220PA01X+003520Y+033344               S0      
327PWM_EXP_A                          A04X-002756Y+033220X1970Y0320     S0      
317PWM_EXP_A        VIA        MD0280PA04X+001400Y+033600               S0      
317PWM_EXP_A        VIA        MD0160PA00X+002672Y+033567               S0      
317NNAME00005                   D0220PA01X+003011Y+037413               S0      
327NNAME00005                         A04X-002756Y+034220X1970Y0320     S0      
317NNAME00005       VIA        MD0280PA04X-000272Y+034100               S0      
317NNAME00005       VIA        MD0160PA00X+000149Y+034371               S0      
317NNAME00006                   D0220PA01X+003011Y+036893               S0      
327NNAME00006                         A04X-002756Y+035220X1970Y0320     S0      
317NNAME00006       VIA        MD0280PA04X+000164Y+034776               S0      
317NNAME00006       VIA        MD0160PA00X+000569Y+034371               S0      
317P5VA                         D0340PA01X+061780Y+040874               S0      
327P5VA                               A01X-002756Y+030220X1970Y0320     S0      
317P5VA             VIA        MD0280PA04X+002090Y+032544               S0      
317P5VA             VIA        MD0280PA04X+053640Y+041894               S0      
317P5VA             VIA        MD0160PA00X+000233Y+031865               S0      
317P5VA             VIA        MD0160PA00X+061780Y+041300               S0      
317TPS2490_LED                  D0340PA01X+063449Y+007200               S0      
317TPS2490_LED                  D0340PA01X+061800Y+007170               S0      
317TPS2490_LED      VIA        MD0280PA01X+062350Y+007150               S0      
327EMITTER_K                          A01X+055050Y+032994X0550Y0450     S0      
327EMITTER_K                          A01X+061857Y+034380X0740Y1220     S0      
317EMITTER_K        VIA        MD0280PA01X+062260Y+033174               S0      
327DETECTOR_C                         A01X+061857Y+038750X0740Y1220     S0      
317DETECTOR_C                   D0340PA01X+061780Y+040314               S0      
317DETECTOR_C                   D0340PA01X+061280Y+040304               S0      
317DETECTOR_C       VIA        MD0280PA01X+062490Y+040094               S0      
327IR_SWITCH_E                        A01X+060710Y+038750X0740Y1220     S0      
317IR_SWITCH_E                  D0220PA01X+053354Y+033490               S0      
317IR_SWITCH_E      VIA        MD0280PA01X+052900Y+035350               S0      
317NNAME00007                   D0220PA01X+053364Y+032210               S0      
317NNAME00007                   D0300PA01X+053291Y+031585               S0      
317NNAME00007       VIA        MD0280PA01X+053794Y+032210               S0      
317NNAME00008                   D0220PA01X+052620Y+032200               S0      
317NNAME00008                   D0220PA01X+052620Y+032600               S0      
317NNAME00008                   D0300PA01X+052904Y+030835               S0      
317NNAME00008       VIA        MD0280PA01X+052489Y+033023               S0      
317TRAY_MOSFET_G                D0220PA01X+053354Y+033060               S0      
317TRAY_MOSFET_G                D0220PA01X+052280Y+032200               S0      
317TRAY_MOSFET_G                D0300PA01X+053289Y+030076               S0      
317TRAY_MOSFET_G    VIA        MD0280PA01X+054074Y+030990               S0      
317NNAME00009                   D0220PA01X+005271Y+035580               S0      
317NNAME00009                   D0220PA01X+004307Y+036585               S0      
327NNAME00009                         A01X+005246Y+036335X0160Y0600     S0      
317NNAME00009       VIA        MD0280PA01X+004307Y+036053               S0      
317I2C_C_BUF_EN                 D0220PA01X+004833Y+035585               S0      
327I2C_C_BUF_EN                       A01X+004990Y+036335X0160Y0600     S0      
317I2C_C_BUF_EN     VIA        MD0280PA01X+004304Y+035367               S0      
317NNAME00010                   D0220PA01X+005109Y+038733               S0      
317NNAME00010                   D0220PA01X+004316Y+037729               S0      
327NNAME00010                         A01X+005246Y+037965X0160Y0600     S0      
317NNAME00010       VIA        MD0280PA01X+004316Y+038261               S0      
317NNAME00011                   D0220PA01X+006005Y+038729               S0      
327NNAME00011                         A01X+005758Y+037965X0160Y0600     S0      
317NNAME00011                   D0320PA01X+006741Y+039126               S0      
317NNAME00012                   D0220PA01X+053024Y+032210               S0      
317NNAME00012                   D0220PA01X+053014Y+033060               S0      
317NNAME00012                   D0220PA01X+053024Y+032640               S0      
317NNAME00012                   D0220PA01X+053014Y+033490               S0      
317NNAME00012       VIA        MD0280PA01X+052627Y+033818               S0      
317NNAME00013                   D0220PA01X+005740Y+035586               S0      
317NNAME00013                   D0220PA01X+006609Y+036516               S0      
327NNAME00013                         A01X+005502Y+036335X0160Y0600     S0      
317NNAME00013       VIA        MD0280PA01X+006604Y+035989               S0      
317NNAME00014                   D0220PA01X+005535Y+038737               S0      
317NNAME00014                   D0220PA01X+006615Y+037824               S0      
327NNAME00014                         A01X+005502Y+037965X0160Y0600     S0      
317NNAME00014       VIA        MD0280PA01X+006610Y+038351               S0      
317I2C_C_BUF_SDA                D0220PA01X+053433Y+026897               S0      
317I2C_C_BUF_SDA                D0220PA01X+006955Y+037398               S0      
317I2C_C_BUF_SDA                D0220PA01X+006955Y+037824               S0      
317I2C_C_BUF_SDA    VIA        MD0280PA01X+008100Y+037279               S0      
317I2C_C_BUF_SCL                D0220PA01X+006950Y+036947               S0      
317I2C_C_BUF_SCL                D0220PA01X+053433Y+026397               S0      
317I2C_C_BUF_SCL                D0220PA01X+006949Y+036516               S0      
317I2C_C_BUF_SCL    VIA        MD0280PA01X+007480Y+036947               S0      
317NNAME00015                   D0220PA01X+058111Y+006692               S0      
317NNAME00015                   D0370PA00X+059610Y+006693               S0      
999
